(kicad_pcb
	(version 20260206)
	(generator "pcbnew")
	(generator_version "10.0")
	(general
		(thickness 1.6)
		(legacy_teardrops no)
	)
	(paper "A4")
	(title_block
		(title "12092022_DA0F0TMDCD0_F0T_Management_Board_D_brd_V3_OCP.brd")
		(comment 1 "Grand Teton / footprints 1070-1075 of 1440")
	)
	(layers
		(0 "F.Cu" signal "TOP")
		(4 "In1.Cu" signal "GND")
		(6 "In2.Cu" signal "IN1")
		(8 "In3.Cu" signal "GND1")
		(10 "In4.Cu" signal "IN2")
		(12 "In5.Cu" signal "VCC")
		(14 "In6.Cu" signal "VCC1")
		(16 "In7.Cu" signal "IN3")
		(18 "In8.Cu" signal "GND2")
		(20 "In9.Cu" signal "IN4")
		(22 "In10.Cu" signal "GND3")
		(2 "B.Cu" signal "BOTTOM")
		(9 "F.Adhes" user "F.Adhesive")
		(11 "B.Adhes" user "B.Adhesive")
		(13 "F.Paste" user "Package Geometry/Pastemask Top")
		(15 "B.Paste" user "Package Geometry/Pastemask Bottom")
		(5 "F.SilkS" user "Ref Des/Silkscreen Top")
		(7 "B.SilkS" user "Ref Des/Silkscreen Bottom")
		(1 "F.Mask" user "Board Geometry/Soldermask Top")
		(3 "B.Mask" user "Board Geometry/Soldermask Bottom")
		(17 "Dwgs.User" user "User.Drawings")
		(19 "Cmts.User" user "User.Comments")
		(21 "Eco1.User" user "User.Eco1")
		(23 "Eco2.User" user "User.Eco2")
		(25 "Edge.Cuts" user "Board Geometry/Outline")
		(27 "Margin" user)
		(31 "F.CrtYd" user "Package Geometry/Place Bound Top")
		(29 "B.CrtYd" user "Package Geometry/Place Bound Bottom")
		(35 "F.Fab" user "Ref Des/Assembly Top")
		(33 "B.Fab" user "Ref Des/Assembly Bottom")
	)
	(footprint ""
		(layer "B.Cu")
		(at 12.319 -97.536)
		(property "Reference" "R317"
			(at 0 0 0)
			(layer "B.SilkS")
			(hide yes)
			(effects
				(font
					(size 1.27 1.27)
				)
				(justify mirror)
			)
		)
		(property "Value" ""
			(at 0 0 0)
			(layer "B.Fab")
			(effects
				(font
					(size 1.27 1.27)
				)
				(justify mirror)
			)
		)
		(duplicate_pad_numbers_are_jumpers no)
		(fp_line
			(start -0.7874 -0.4064)
			(end -0.7874 0.4064)
			(stroke
				(width 0.1524)
				(type default)
			)
			(layer "B.SilkS")
		)
		(fp_line
			(start -0.7874 0.4064)
			(end 0.7874 0.4064)
			(stroke
				(width 0.1524)
				(type default)
			)
			(layer "B.SilkS")
		)
		(fp_line
			(start 0.7874 -0.4064)
			(end -0.7874 -0.4064)
			(stroke
				(width 0.1524)
				(type default)
			)
			(layer "B.SilkS")
		)
		(fp_line
			(start 0.7874 0.4064)
			(end 0.7874 -0.4064)
			(stroke
				(width 0.1524)
				(type default)
			)
			(layer "B.SilkS")
		)
		(fp_line
			(start -0.67945 -0.3048)
			(end -0.67945 0.3048)
			(stroke
				(width 0.1)
				(type default)
			)
			(layer "B.Fab")
		)
		(fp_line
			(start -0.67945 0.3048)
			(end -0.120396 0.3048)
			(stroke
				(width 0.1)
				(type default)
			)
			(layer "B.Fab")
		)
		(fp_line
			(start -0.12065 -0.3048)
			(end -0.67945 -0.3048)
			(stroke
				(width 0.1)
				(type default)
			)
			(layer "B.Fab")
		)
		(fp_line
			(start -0.12065 -0.2794)
			(end -0.12065 -0.3048)
			(stroke
				(width 0.1)
				(type default)
			)
			(layer "B.Fab")
		)
		(fp_line
			(start -0.120396 0.2794)
			(end 0.12065 0.2794)
			(stroke
				(width 0.1)
				(type default)
			)
			(layer "B.Fab")
		)
		(fp_line
			(start -0.120396 0.3048)
			(end -0.120396 0.2794)
			(stroke
				(width 0.1)
				(type default)
			)
			(layer "B.Fab")
		)
		(fp_line
			(start 0.12065 -0.305054)
			(end 0.12065 -0.2794)
			(stroke
				(width 0.1)
				(type default)
			)
			(layer "B.Fab")
		)
		(fp_line
			(start 0.12065 -0.2794)
			(end -0.12065 -0.2794)
			(stroke
				(width 0.1)
				(type default)
			)
			(layer "B.Fab")
		)
		(fp_line
			(start 0.12065 0.2794)
			(end 0.12065 0.3048)
			(stroke
				(width 0.1)
				(type default)
			)
			(layer "B.Fab")
		)
		(fp_line
			(start 0.12065 0.3048)
			(end 0.67945 0.3048)
			(stroke
				(width 0.1)
				(type default)
			)
			(layer "B.Fab")
		)
		(fp_line
			(start 0.67945 -0.305054)
			(end 0.12065 -0.305054)
			(stroke
				(width 0.1)
				(type default)
			)
			(layer "B.Fab")
		)
		(fp_line
			(start 0.67945 0.3048)
			(end 0.67945 -0.305054)
			(stroke
				(width 0.1)
				(type default)
			)
			(layer "B.Fab")
		)
		(pad "1" smd circle
			(at 0.40005 0 180)
			(size 0 0)
			(layers "B.Cu" "B.Mask" "B.Paste")
			(net "PWR_LED_CPLD")
		)
		(pad "2" smd circle
			(at -0.40005 0 180)
			(size 0 0)
			(layers "B.Cu" "B.Mask" "B.Paste")
			(net "PWR_LED")
		)
	)
	(footprint ""
		(layer "B.Cu")
		(at 74.717148 -93.358208 -90)
		(property "Reference" "R42"
			(at 0 0 90)
			(layer "B.SilkS")
			(hide yes)
			(effects
				(font
					(size 1.27 1.27)
				)
				(justify mirror)
			)
		)
		(property "Value" ""
			(at 0 0 90)
			(layer "B.Fab")
			(effects
				(font
					(size 1.27 1.27)
				)
				(justify mirror)
			)
		)
		(duplicate_pad_numbers_are_jumpers no)
		(fp_line
			(start -0.7874 0.4064)
			(end 0.7874 0.4064)
			(stroke
				(width 0.1524)
				(type default)
			)
			(layer "B.SilkS")
		)
		(fp_line
			(start 0.7874 0.4064)
			(end 0.7874 -0.4064)
			(stroke
				(width 0.1524)
				(type default)
			)
			(layer "B.SilkS")
		)
		(fp_line
			(start -0.7874 -0.4064)
			(end -0.7874 0.4064)
			(stroke
				(width 0.1524)
				(type default)
			)
			(layer "B.SilkS")
		)
		(fp_line
			(start 0.7874 -0.4064)
			(end -0.7874 -0.4064)
			(stroke
				(width 0.1524)
				(type default)
			)
			(layer "B.SilkS")
		)
		(fp_line
			(start -0.67945 0.3048)
			(end -0.120396 0.3048)
			(stroke
				(width 0.1)
				(type default)
			)
			(layer "B.Fab")
		)
		(fp_line
			(start -0.120396 0.3048)
			(end -0.120396 0.2794)
			(stroke
				(width 0.1)
				(type default)
			)
			(layer "B.Fab")
		)
		(fp_line
			(start 0.12065 0.3048)
			(end 0.67945 0.3048)
			(stroke
				(width 0.1)
				(type default)
			)
			(layer "B.Fab")
		)
		(fp_line
			(start 0.67945 0.3048)
			(end 0.67945 -0.305054)
			(stroke
				(width 0.1)
				(type default)
			)
			(layer "B.Fab")
		)
		(fp_line
			(start -0.120396 0.2794)
			(end 0.12065 0.2794)
			(stroke
				(width 0.1)
				(type default)
			)
			(layer "B.Fab")
		)
		(fp_line
			(start 0.12065 0.2794)
			(end 0.12065 0.3048)
			(stroke
				(width 0.1)
				(type default)
			)
			(layer "B.Fab")
		)
		(fp_line
			(start -0.12065 -0.2794)
			(end -0.12065 -0.3048)
			(stroke
				(width 0.1)
				(type default)
			)
			(layer "B.Fab")
		)
		(fp_line
			(start 0.12065 -0.2794)
			(end -0.12065 -0.2794)
			(stroke
				(width 0.1)
				(type default)
			)
			(layer "B.Fab")
		)
		(fp_line
			(start -0.67945 -0.3048)
			(end -0.67945 0.3048)
			(stroke
				(width 0.1)
				(type default)
			)
			(layer "B.Fab")
		)
		(fp_line
			(start -0.12065 -0.3048)
			(end -0.67945 -0.3048)
			(stroke
				(width 0.1)
				(type default)
			)
			(layer "B.Fab")
		)
		(fp_line
			(start 0.12065 -0.305054)
			(end 0.12065 -0.2794)
			(stroke
				(width 0.1)
				(type default)
			)
			(layer "B.Fab")
		)
		(fp_line
			(start 0.67945 -0.305054)
			(end 0.12065 -0.305054)
			(stroke
				(width 0.1)
				(type default)
			)
			(layer "B.Fab")
		)
		(pad "1" smd circle
			(at 0.40005 0 90)
			(size 0 0)
			(layers "B.Cu" "B.Mask" "B.Paste")
			(net "P3V3_AUX")
		)
		(pad "2" smd circle
			(at -0.40005 0 90)
			(size 0 0)
			(layers "B.Cu" "B.Mask" "B.Paste")
			(net "Q7_D")
		)
	)
	(footprint ""
		(layer "B.Cu")
		(at 71.858378 -47.106332 -90)
		(property "Reference" "R374"
			(at 0 0 90)
			(layer "B.SilkS")
			(hide yes)
			(effects
				(font
					(size 1.27 1.27)
				)
				(justify mirror)
			)
		)
		(property "Value" ""
			(at 0 0 90)
			(layer "B.Fab")
			(effects
				(font
					(size 1.27 1.27)
				)
				(justify mirror)
			)
		)
		(duplicate_pad_numbers_are_jumpers no)
		(fp_line
			(start -0.7874 0.4064)
			(end 0.7874 0.4064)
			(stroke
				(width 0.1524)
				(type default)
			)
			(layer "B.SilkS")
		)
		(fp_line
			(start 0.7874 0.4064)
			(end 0.7874 -0.4064)
			(stroke
				(width 0.1524)
				(type default)
			)
			(layer "B.SilkS")
		)
		(fp_line
			(start -0.7874 -0.4064)
			(end -0.7874 0.4064)
			(stroke
				(width 0.1524)
				(type default)
			)
			(layer "B.SilkS")
		)
		(fp_line
			(start 0.7874 -0.4064)
			(end -0.7874 -0.4064)
			(stroke
				(width 0.1524)
				(type default)
			)
			(layer "B.SilkS")
		)
		(fp_line
			(start -0.67945 0.3048)
			(end -0.120396 0.3048)
			(stroke
				(width 0.1)
				(type default)
			)
			(layer "B.Fab")
		)
		(fp_line
			(start -0.120396 0.3048)
			(end -0.120396 0.2794)
			(stroke
				(width 0.1)
				(type default)
			)
			(layer "B.Fab")
		)
		(fp_line
			(start 0.12065 0.3048)
			(end 0.67945 0.3048)
			(stroke
				(width 0.1)
				(type default)
			)
			(layer "B.Fab")
		)
		(fp_line
			(start 0.67945 0.3048)
			(end 0.67945 -0.305054)
			(stroke
				(width 0.1)
				(type default)
			)
			(layer "B.Fab")
		)
		(fp_line
			(start -0.120396 0.2794)
			(end 0.12065 0.2794)
			(stroke
				(width 0.1)
				(type default)
			)
			(layer "B.Fab")
		)
		(fp_line
			(start 0.12065 0.2794)
			(end 0.12065 0.3048)
			(stroke
				(width 0.1)
				(type default)
			)
			(layer "B.Fab")
		)
		(fp_line
			(start -0.12065 -0.2794)
			(end -0.12065 -0.3048)
			(stroke
				(width 0.1)
				(type default)
			)
			(layer "B.Fab")
		)
		(fp_line
			(start 0.12065 -0.2794)
			(end -0.12065 -0.2794)
			(stroke
				(width 0.1)
				(type default)
			)
			(layer "B.Fab")
		)
		(fp_line
			(start -0.67945 -0.3048)
			(end -0.67945 0.3048)
			(stroke
				(width 0.1)
				(type default)
			)
			(layer "B.Fab")
		)
		(fp_line
			(start -0.12065 -0.3048)
			(end -0.67945 -0.3048)
			(stroke
				(width 0.1)
				(type default)
			)
			(layer "B.Fab")
		)
		(fp_line
			(start 0.12065 -0.305054)
			(end 0.12065 -0.2794)
			(stroke
				(width 0.1)
				(type default)
			)
			(layer "B.Fab")
		)
		(fp_line
			(start 0.67945 -0.305054)
			(end 0.12065 -0.305054)
			(stroke
				(width 0.1)
				(type default)
			)
			(layer "B.Fab")
		)
		(pad "1" smd circle
			(at 0.40005 0 90)
			(size 0 0)
			(layers "B.Cu" "B.Mask" "B.Paste")
			(net "M_BMC_DDR4_MCKE")
		)
		(pad "2" smd circle
			(at -0.40005 0 90)
			(size 0 0)
			(layers "B.Cu" "B.Mask" "B.Paste")
			(net "P1V2_AUX")
		)
	)
	(footprint ""
		(layer "B.Cu")
		(at 56.462422 -72.46239 90)
		(property "Reference" "R784"
			(at 0 0 90)
			(layer "B.SilkS")
			(hide yes)
			(effects
				(font
					(size 1.27 1.27)
				)
				(justify mirror)
			)
		)
		(property "Value" ""
			(at 0 0 90)
			(layer "B.Fab")
			(effects
				(font
					(size 1.27 1.27)
				)
				(justify mirror)
			)
		)
		(duplicate_pad_numbers_are_jumpers no)
		(fp_line
			(start 0.7874 -0.4064)
			(end -0.7874 -0.4064)
			(stroke
				(width 0.1524)
				(type default)
			)
			(layer "B.SilkS")
		)
		(fp_line
			(start -0.7874 -0.4064)
			(end -0.7874 0.4064)
			(stroke
				(width 0.1524)
				(type default)
			)
			(layer "B.SilkS")
		)
		(fp_line
			(start 0.7874 0.4064)
			(end 0.7874 -0.4064)
			(stroke
				(width 0.1524)
				(type default)
			)
			(layer "B.SilkS")
		)
		(fp_line
			(start -0.7874 0.4064)
			(end 0.7874 0.4064)
			(stroke
				(width 0.1524)
				(type default)
			)
			(layer "B.SilkS")
		)
		(fp_line
			(start 0.67945 -0.305054)
			(end 0.12065 -0.305054)
			(stroke
				(width 0.1)
				(type default)
			)
			(layer "B.Fab")
		)
		(fp_line
			(start 0.12065 -0.305054)
			(end 0.12065 -0.2794)
			(stroke
				(width 0.1)
				(type default)
			)
			(layer "B.Fab")
		)
		(fp_line
			(start -0.12065 -0.3048)
			(end -0.67945 -0.3048)
			(stroke
				(width 0.1)
				(type default)
			)
			(layer "B.Fab")
		)
		(fp_line
			(start -0.67945 -0.3048)
			(end -0.67945 0.3048)
			(stroke
				(width 0.1)
				(type default)
			)
			(layer "B.Fab")
		)
		(fp_line
			(start 0.12065 -0.2794)
			(end -0.12065 -0.2794)
			(stroke
				(width 0.1)
				(type default)
			)
			(layer "B.Fab")
		)
		(fp_line
			(start -0.12065 -0.2794)
			(end -0.12065 -0.3048)
			(stroke
				(width 0.1)
				(type default)
			)
			(layer "B.Fab")
		)
		(fp_line
			(start 0.12065 0.2794)
			(end 0.12065 0.3048)
			(stroke
				(width 0.1)
				(type default)
			)
			(layer "B.Fab")
		)
		(fp_line
			(start -0.120396 0.2794)
			(end 0.12065 0.2794)
			(stroke
				(width 0.1)
				(type default)
			)
			(layer "B.Fab")
		)
		(fp_line
			(start 0.67945 0.3048)
			(end 0.67945 -0.305054)
			(stroke
				(width 0.1)
				(type default)
			)
			(layer "B.Fab")
		)
		(fp_line
			(start 0.12065 0.3048)
			(end 0.67945 0.3048)
			(stroke
				(width 0.1)
				(type default)
			)
			(layer "B.Fab")
		)
		(fp_line
			(start -0.120396 0.3048)
			(end -0.120396 0.2794)
			(stroke
				(width 0.1)
				(type default)
			)
			(layer "B.Fab")
		)
		(fp_line
			(start -0.67945 0.3048)
			(end -0.120396 0.3048)
			(stroke
				(width 0.1)
				(type default)
			)
			(layer "B.Fab")
		)
		(pad "1" smd circle
			(at 0.40005 0 270)
			(size 0 0)
			(layers "B.Cu" "B.Mask" "B.Paste")
			(net "P1V2_AUX")
		)
		(pad "2" smd circle
			(at -0.40005 0 270)
			(size 0 0)
			(layers "B.Cu" "B.Mask" "B.Paste")
			(net "ADCVREFEXT0")
		)
	)
	(footprint ""
		(layer "B.Cu")
		(at 62.442344 -34.637726 90)
		(property "Reference" "R567"
			(at 0 0 90)
			(layer "B.SilkS")
			(hide yes)
			(effects
				(font
					(size 1.27 1.27)
				)
				(justify mirror)
			)
		)
		(property "Value" ""
			(at 0 0 90)
			(layer "B.Fab")
			(effects
				(font
					(size 1.27 1.27)
				)
				(justify mirror)
			)
		)
		(duplicate_pad_numbers_are_jumpers no)
		(fp_line
			(start 0.7874 -0.4064)
			(end -0.7874 -0.4064)
			(stroke
				(width 0.1524)
				(type default)
			)
			(layer "B.SilkS")
		)
		(fp_line
			(start -0.7874 -0.4064)
			(end -0.7874 0.4064)
			(stroke
				(width 0.1524)
				(type default)
			)
			(layer "B.SilkS")
		)
		(fp_line
			(start 0.7874 0.4064)
			(end 0.7874 -0.4064)
			(stroke
				(width 0.1524)
				(type default)
			)
			(layer "B.SilkS")
		)
		(fp_line
			(start -0.7874 0.4064)
			(end 0.7874 0.4064)
			(stroke
				(width 0.1524)
				(type default)
			)
			(layer "B.SilkS")
		)
		(fp_line
			(start 0.67945 -0.305054)
			(end 0.12065 -0.305054)
			(stroke
				(width 0.1)
				(type default)
			)
			(layer "B.Fab")
		)
		(fp_line
			(start 0.12065 -0.305054)
			(end 0.12065 -0.2794)
			(stroke
				(width 0.1)
				(type default)
			)
			(layer "B.Fab")
		)
		(fp_line
			(start -0.12065 -0.3048)
			(end -0.67945 -0.3048)
			(stroke
				(width 0.1)
				(type default)
			)
			(layer "B.Fab")
		)
		(fp_line
			(start -0.67945 -0.3048)
			(end -0.67945 0.3048)
			(stroke
				(width 0.1)
				(type default)
			)
			(layer "B.Fab")
		)
		(fp_line
			(start 0.12065 -0.2794)
			(end -0.12065 -0.2794)
			(stroke
				(width 0.1)
				(type default)
			)
			(layer "B.Fab")
		)
		(fp_line
			(start -0.12065 -0.2794)
			(end -0.12065 -0.3048)
			(stroke
				(width 0.1)
				(type default)
			)
			(layer "B.Fab")
		)
		(fp_line
			(start 0.12065 0.2794)
			(end 0.12065 0.3048)
			(stroke
				(width 0.1)
				(type default)
			)
			(layer "B.Fab")
		)
		(fp_line
			(start -0.120396 0.2794)
			(end 0.12065 0.2794)
			(stroke
				(width 0.1)
				(type default)
			)
			(layer "B.Fab")
		)
		(fp_line
			(start 0.67945 0.3048)
			(end 0.67945 -0.305054)
			(stroke
				(width 0.1)
				(type default)
			)
			(layer "B.Fab")
		)
		(fp_line
			(start 0.12065 0.3048)
			(end 0.67945 0.3048)
			(stroke
				(width 0.1)
				(type default)
			)
			(layer "B.Fab")
		)
		(fp_line
			(start -0.120396 0.3048)
			(end -0.120396 0.2794)
			(stroke
				(width 0.1)
				(type default)
			)
			(layer "B.Fab")
		)
		(fp_line
			(start -0.67945 0.3048)
			(end -0.120396 0.3048)
			(stroke
				(width 0.1)
				(type default)
			)
			(layer "B.Fab")
		)
		(pad "1" smd circle
			(at 0.40005 0 270)
			(size 0 0)
			(layers "B.Cu" "B.Mask" "B.Paste")
			(net "SMB_BMC_MM7_R_SCL")
		)
		(pad "2" smd circle
			(at -0.40005 0 270)
			(size 0 0)
			(layers "B.Cu" "B.Mask" "B.Paste")
			(net "SMB_BMC_MM7_SCL")
		)
	)
	(footprint ""
		(layer "B.Cu")
		(at 17.907 -19.431)
		(property "Reference" "R417"
			(at 0 0 0)
			(layer "B.SilkS")
			(hide yes)
			(effects
				(font
					(size 1.27 1.27)
				)
				(justify mirror)
			)
		)
		(property "Value" ""
			(at 0 0 0)
			(layer "B.Fab")
			(effects
				(font
					(size 1.27 1.27)
				)
				(justify mirror)
			)
		)
		(duplicate_pad_numbers_are_jumpers no)
		(fp_line
			(start -0.7874 -0.4064)
			(end -0.7874 0.4064)
			(stroke
				(width 0.1524)
				(type default)
			)
			(layer "B.SilkS")
		)
		(fp_line
			(start -0.7874 0.4064)
			(end 0.7874 0.4064)
			(stroke
				(width 0.1524)
				(type default)
			)
			(layer "B.SilkS")
		)
		(fp_line
			(start 0.7874 -0.4064)
			(end -0.7874 -0.4064)
			(stroke
				(width 0.1524)
				(type default)
			)
			(layer "B.SilkS")
		)
		(fp_line
			(start 0.7874 0.4064)
			(end 0.7874 -0.4064)
			(stroke
				(width 0.1524)
				(type default)
			)
			(layer "B.SilkS")
		)
		(fp_line
			(start -0.67945 -0.3048)
			(end -0.67945 0.3048)
			(stroke
				(width 0.1)
				(type default)
			)
			(layer "B.Fab")
		)
		(fp_line
			(start -0.67945 0.3048)
			(end -0.120396 0.3048)
			(stroke
				(width 0.1)
				(type default)
			)
			(layer "B.Fab")
		)
		(fp_line
			(start -0.12065 -0.3048)
			(end -0.67945 -0.3048)
			(stroke
				(width 0.1)
				(type default)
			)
			(layer "B.Fab")
		)
		(fp_line
			(start -0.12065 -0.2794)
			(end -0.12065 -0.3048)
			(stroke
				(width 0.1)
				(type default)
			)
			(layer "B.Fab")
		)
		(fp_line
			(start -0.120396 0.2794)
			(end 0.12065 0.2794)
			(stroke
				(width 0.1)
				(type default)
			)
			(layer "B.Fab")
		)
		(fp_line
			(start -0.120396 0.3048)
			(end -0.120396 0.2794)
			(stroke
				(width 0.1)
				(type default)
			)
			(layer "B.Fab")
		)
		(fp_line
			(start 0.12065 -0.305054)
			(end 0.12065 -0.2794)
			(stroke
				(width 0.1)
				(type default)
			)
			(layer "B.Fab")
		)
		(fp_line
			(start 0.12065 -0.2794)
			(end -0.12065 -0.2794)
			(stroke
				(width 0.1)
				(type default)
			)
			(layer "B.Fab")
		)
		(fp_line
			(start 0.12065 0.2794)
			(end 0.12065 0.3048)
			(stroke
				(width 0.1)
				(type default)
			)
			(layer "B.Fab")
		)
		(fp_line
			(start 0.12065 0.3048)
			(end 0.67945 0.3048)
			(stroke
				(width 0.1)
				(type default)
			)
			(layer "B.Fab")
		)
		(fp_line
			(start 0.67945 -0.305054)
			(end 0.12065 -0.305054)
			(stroke
				(width 0.1)
				(type default)
			)
			(layer "B.Fab")
		)
		(fp_line
			(start 0.67945 0.3048)
			(end 0.67945 -0.305054)
			(stroke
				(width 0.1)
				(type default)
			)
			(layer "B.Fab")
		)
		(pad "1" smd circle
			(at 0.40005 0 180)
			(size 0 0)
			(layers "B.Cu" "B.Mask" "B.Paste")
			(net "TMC75_A0")
		)
		(pad "2" smd circle
			(at -0.40005 0 180)
			(size 0 0)
			(layers "B.Cu" "B.Mask" "B.Paste")
			(net "GND")
		)
	)
)
